# T6G (Grand Teton) — schematic netlist excerpt (pin names and nets, part order shuffled) for the footprints in the layout excerpt that follows; sources: Cadence DE-HDL packaged netlist, KiCad conversion of 04192023_DAF0TMB3IC0_F0TG_MB_C_brd_V02_OCP.brd

U225  74LVC1G126SE7  74LVC1G126SE-7 IC  pkg SOT353_0-65_2X1-25  page 139
  OE  = OCP_V3_2_AUX_PWR_EN_R3
  A  = RST_SMB_SWITCH_N
  GND  = GND
  Y  = RST_HP_OCP_V3_2_R_N
  VCC  = P3V3_AUX

(kicad_pcb
	(version 20260206)
	(generator "pcbnew")
	(generator_version "10.0")
	(general
		(thickness 1.6)
		(legacy_teardrops no)
	)
	(paper "A4")
	(title_block
		(title "04192023_DAF0TMB3IC0_F0TG_MB_C_brd_V02_OCP.brd")
		(comment 1 "Grand Teton / footprints 3670-3670 of 8354")
	)
	(layers
		(0 "F.Cu" signal "TOP")
		(4 "In1.Cu" signal "GND")
		(6 "In2.Cu" signal "IN1")
		(8 "In3.Cu" signal "GND1")
		(10 "In4.Cu" signal "IN2")
		(12 "In5.Cu" signal "GND2")
		(14 "In6.Cu" signal "IN3")
		(16 "In7.Cu" signal "GND3")
		(18 "In8.Cu" signal "VCC")
		(20 "In9.Cu" signal "VCC1")
		(22 "In10.Cu" signal "GND4")
		(24 "In11.Cu" signal "IN4")
		(26 "In12.Cu" signal "GND5")
		(28 "In13.Cu" signal "IN5")
		(30 "In14.Cu" signal "GND6")
		(32 "In15.Cu" signal "IN6")
		(34 "In16.Cu" signal "GND7")
		(2 "B.Cu" signal "BOTTOM")
		(9 "F.Adhes" user "F.Adhesive")
		(11 "B.Adhes" user "B.Adhesive")
		(13 "F.Paste" user "Package Geometry/Pastemask Top")
		(15 "B.Paste" user "Package Geometry/Pastemask Bottom")
		(5 "F.SilkS" user "Ref Des/Silkscreen Top")
		(7 "B.SilkS" user "Ref Des/Silkscreen Bottom")
		(1 "F.Mask" user "Board Geometry/Soldermask Top")
		(3 "B.Mask" user "Board Geometry/Soldermask Bottom")
		(17 "Dwgs.User" user "User.Drawings")
		(19 "Cmts.User" user "User.Comments")
		(21 "Eco1.User" user "User.Eco1")
		(23 "Eco2.User" user "User.Eco2")
		(25 "Edge.Cuts" user "Board Geometry/Outline")
		(27 "Margin" user)
		(31 "F.CrtYd" user "Package Geometry/Place Bound Top")
		(29 "B.CrtYd" user "Package Geometry/Place Bound Bottom")
		(35 "F.Fab" user "Ref Des/Assembly Top")
		(33 "B.Fab" user "Ref Des/Assembly Bottom")
	)
	(footprint ""
		(layer "F.Cu")
		(at 52.22748 -29.657548 90)
		(property "Reference" "U225"
			(at -2.483612 3.139948 90)
			(unlocked yes)
			(layer "F.SilkS")
			(effects
				(font
					(size 0.7874 0.5842)
					(thickness 0.1524)
				)
				(justify left)
			)
		)
		(property "Value" ""
			(at 0 0 90)
			(layer "F.Fab")
			(effects
				(font
					(size 1.27 1.27)
				)
			)
		)
		(duplicate_pad_numbers_are_jumpers no)
		(fp_line
			(start 1.400048 -1.100074)
			(end -1.400048 -1.100074)
			(stroke
				(width 0.1524)
				(type default)
			)
			(layer "F.SilkS")
		)
		(fp_line
			(start 1.400048 -1.100074)
			(end 1.400048 1.100074)
			(stroke
				(width 0.1524)
				(type default)
			)
			(layer "F.SilkS")
		)
		(fp_line
			(start 1.400048 1.100074)
			(end -1.400048 1.100074)
			(stroke
				(width 0.1524)
				(type default)
			)
			(layer "F.SilkS")
		)
		(fp_line
			(start -1.400048 1.100074)
			(end -1.400048 -1.100074)
			(stroke
				(width 0.1524)
				(type default)
			)
			(layer "F.SilkS")
		)
		(fp_poly
			(pts
				(xy -2.606548 -0.141986) (xy -2.606548 -1.157986) (xy -1.590548 -0.649986)
			)
			(stroke
				(width 0)
				(type default)
			)
			(fill yes)
			(layer "F.SilkS")
		)
		(fp_line
			(start 0.674878 -1.100074)
			(end 0.674878 1.100074)
			(stroke
				(width 0.1)
				(type default)
			)
			(layer "F.Fab")
		)
		(fp_line
			(start -0.674878 -1.100074)
			(end 0.674878 -1.100074)
			(stroke
				(width 0.1)
				(type default)
			)
			(layer "F.Fab")
		)
		(fp_line
			(start 0.674878 1.100074)
			(end -0.674878 1.100074)
			(stroke
				(width 0.1)
				(type default)
			)
			(layer "F.Fab")
		)
		(fp_line
			(start -0.674878 1.100074)
			(end -0.674878 -1.100074)
			(stroke
				(width 0.1)
				(type default)
			)
			(layer "F.Fab")
		)
		(fp_poly
			(pts
				(xy -1.590548 -0.649986) (xy -2.606548 -1.157986) (xy -2.606548 -0.141986)
			)
			(stroke
				(width 0)
				(type default)
			)
			(fill yes)
			(layer "F.Fab")
		)
		(pad "1" smd rect
			(at -0.94996 -0.649986)
			(size 0.4318 0.6096)
			(layers "F.Cu" "F.Mask" "F.Paste")
			(net "OCP_V3_2_AUX_PWR_EN_R3")
		)
		(pad "2" smd rect
			(at -0.94996 0)
			(size 0.4318 0.6096)
			(layers "F.Cu" "F.Mask" "F.Paste")
			(net "RST_SMB_SWITCH_N")
		)
		(pad "3" smd rect
			(at -0.94996 0.649986)
			(size 0.4318 0.6096)
			(layers "F.Cu" "F.Mask" "F.Paste")
			(net "GND")
		)
		(pad "4" smd rect
			(at 0.94996 0.649986)
			(size 0.4318 0.6096)
			(layers "F.Cu" "F.Mask" "F.Paste")
			(net "RST_HP_OCP_V3_2_R_N")
		)
		(pad "5" smd rect
			(at 0.94996 -0.649986)
			(size 0.4318 0.6096)
			(layers "F.Cu" "F.Mask" "F.Paste")
			(net "P3V3_AUX")
		)
	)
)
